(kicad_pcb
	(version 20260206)
	(generator "pcbnew")
	(generator_version "10.0")
	(general
		(thickness 1.6)
		(legacy_teardrops no)
	)
	(paper "A4")
	(title_block
		(title "dpb — 14545-sa.0730WZS0815.brd")
		(comment 1 "Honey Badger (Wiwynn) / footprints 650-657 of 1066")
	)
	(layers
		(0 "F.Cu" signal "TOP")
		(4 "In1.Cu" signal "L2GND")
		(6 "In2.Cu" signal "L3")
		(8 "In3.Cu" signal "L4VCC")
		(10 "In4.Cu" signal "L5VCC")
		(12 "In5.Cu" signal "L6")
		(14 "In6.Cu" signal "L7GND")
		(2 "B.Cu" signal "BOTTOM")
		(9 "F.Adhes" user "F.Adhesive")
		(11 "B.Adhes" user "B.Adhesive")
		(13 "F.Paste" user "Package Geometry/Pastemask Top")
		(15 "B.Paste" user "Package Geometry/Pastemask Bottom")
		(5 "F.SilkS" user "Ref Des/Silkscreen Top")
		(7 "B.SilkS" user "Ref Des/Silkscreen Bottom")
		(1 "F.Mask" user "Board Geometry/Soldermask Top")
		(3 "B.Mask" user "Board Geometry/Soldermask Bottom")
		(17 "Dwgs.User" user "User.Drawings")
		(19 "Cmts.User" user "User.Comments")
		(21 "Eco1.User" user "User.Eco1")
		(23 "Eco2.User" user "User.Eco2")
		(25 "Edge.Cuts" user "Board Geometry/Outline")
		(27 "Margin" user)
		(31 "F.CrtYd" user "Package Geometry/Place Bound Top")
		(29 "B.CrtYd" user "Package Geometry/Place Bound Bottom")
		(35 "F.Fab" user "Ref Des/Assembly Top")
		(33 "B.Fab" user "Ref Des/Assembly Bottom")
	)
	(footprint ""
		(layer "F.Cu")
		(at 5.079746 -496.8367 90)
		(property "Reference" "PC32"
			(at 0 0 90)
			(layer "F.SilkS")
			(hide yes)
			(effects
				(font
					(size 1.27 1.27)
				)
			)
		)
		(property "Value" "SC680P50V2KX-2GP"
			(at 1.1811 -2.7051 90)
			(unlocked yes)
			(layer "F.Fab")
			(hide yes)
			(effects
				(font
					(size 1.016 1.016)
					(thickness 0.1524)
				)
			)
		)
		(property "Device Type" "C402H22"
			(at 1.1811 -4.2291 90)
			(unlocked yes)
			(layer "F.Fab")
			(hide yes)
			(effects
				(font
					(size 1.016 1.016)
					(thickness 0.1524)
				)
			)
		)
		(duplicate_pad_numbers_are_jumpers no)
		(fp_rect
			(start -0.4318 0.9525)
			(end 0.4318 -0.9525)
			(stroke
				(width 0)
				(type default)
			)
			(fill no)
			(layer "F.CrtYd")
		)
		(fp_rect
			(start -0.4318 0.9525)
			(end 0.4318 -0.9525)
			(stroke
				(width 0)
				(type default)
			)
			(fill no)
			(layer "F.Fab")
		)
		(pad "1" smd custom
			(at 0 -0.4445 90)
			(size 0.1524 0.1524)
			(layers "F.Cu" "F.Mask" "F.Paste")
			(net "P5VC_LL_NET")
			(options
				(clearance outline)
				(anchor circle)
			)
			(primitives
				(gr_poly
					(pts
						(arc
							(start 0.3048 -0.2032)
							(mid 0.275042 -0.275042)
							(end 0.2032 -0.3048)
						)
						(arc
							(start -0.2032 -0.3048)
							(mid -0.275042 -0.275042)
							(end -0.3048 -0.2032)
						)
						(arc
							(start -0.3048 0.2032)
							(mid -0.275042 0.275042)
							(end -0.2032 0.3048)
						)
						(arc
							(start 0.2032 0.3048)
							(mid 0.275042 0.275042)
							(end 0.3048 0.2032)
						)
					)
					(width 0)
					(fill yes)
				)
			)
		)
		(pad "2" smd custom
			(at 0 0.4445 90)
			(size 0.1524 0.1524)
			(layers "F.Cu" "F.Mask" "F.Paste")
			(net "P5VC_VFB")
			(options
				(clearance outline)
				(anchor circle)
			)
			(primitives
				(gr_poly
					(pts
						(arc
							(start 0.3048 -0.2032)
							(mid 0.275042 -0.275042)
							(end 0.2032 -0.3048)
						)
						(arc
							(start -0.2032 -0.3048)
							(mid -0.275042 -0.275042)
							(end -0.3048 -0.2032)
						)
						(arc
							(start -0.3048 0.2032)
							(mid -0.275042 0.275042)
							(end -0.2032 0.3048)
						)
						(arc
							(start 0.2032 0.3048)
							(mid 0.275042 0.275042)
							(end 0.3048 0.2032)
						)
					)
					(width 0)
					(fill yes)
				)
			)
		)
	)
	(footprint ""
		(layer "F.Cu")
		(at 211.0232 -438.4548 -90)
		(property "Reference" "PC43"
			(at 0 0 270)
			(layer "F.SilkS")
			(hide yes)
			(effects
				(font
					(size 1.27 1.27)
				)
			)
		)
		(property "Value" "SC22U16V6MX-GP"
			(at -0.0762 -5.1308 270)
			(unlocked yes)
			(layer "F.Fab")
			(hide yes)
			(effects
				(font
					(size 1.016 1.016)
					(thickness 0.1524)
				)
			)
		)
		(property "Device Type" "C1206H71"
			(at -0.127 -6.6548 270)
			(unlocked yes)
			(layer "F.Fab")
			(hide yes)
			(effects
				(font
					(size 1.016 1.016)
					(thickness 0.1524)
				)
			)
		)
		(duplicate_pad_numbers_are_jumpers no)
		(fp_line
			(start -1.016 2.2352)
			(end -1.016 0.8382)
			(stroke
				(width 0.1524)
				(type default)
			)
			(layer "F.SilkS")
		)
		(fp_line
			(start 1.016 2.2352)
			(end -1.016 2.2352)
			(stroke
				(width 0.1524)
				(type default)
			)
			(layer "F.SilkS")
		)
		(fp_line
			(start 1.016 0.8382)
			(end 1.016 2.2352)
			(stroke
				(width 0.1524)
				(type default)
			)
			(layer "F.SilkS")
		)
		(fp_line
			(start -1.016 -0.8382)
			(end -1.016 -2.2352)
			(stroke
				(width 0.1524)
				(type default)
			)
			(layer "F.SilkS")
		)
		(fp_line
			(start -1.016 -2.2352)
			(end 1.016 -2.2352)
			(stroke
				(width 0.1524)
				(type default)
			)
			(layer "F.SilkS")
		)
		(fp_line
			(start 1.016 -2.2352)
			(end 1.016 -0.8382)
			(stroke
				(width 0.1524)
				(type default)
			)
			(layer "F.SilkS")
		)
		(fp_rect
			(start -1.0922 2.3114)
			(end 1.0922 -2.3114)
			(stroke
				(width 0)
				(type default)
			)
			(fill no)
			(layer "F.CrtYd")
		)
		(fp_poly
			(pts
				(xy 1.0922 -2.3114) (xy 1.0922 2.3114) (xy -1.0922 2.3114) (xy -1.0922 -2.3114)
			)
			(stroke
				(width 0)
				(type default)
			)
			(fill no)
			(layer "F.Fab")
		)
		(pad "1" smd rect
			(at 0 -1.397 270)
			(size 1.651 1.27)
			(layers "F.Cu" "F.Mask" "F.Paste")
			(net "P3V3_LX_COOPER")
		)
		(pad "2" smd rect
			(at 0 1.397 270)
			(size 1.651 1.27)
			(layers "F.Cu" "F.Mask" "F.Paste")
			(net "GND")
		)
	)
	(footprint ""
		(layer "F.Cu")
		(at 218.142058 -372.312184 -90)
		(property "Reference" "C120"
			(at 0 0 270)
			(layer "F.SilkS")
			(hide yes)
			(effects
				(font
					(size 1.27 1.27)
				)
			)
		)
		(property "Value" "SCD01U50V2KX-1GP"
			(at 1.1811 -2.7051 270)
			(unlocked yes)
			(layer "F.Fab")
			(hide yes)
			(effects
				(font
					(size 1.016 1.016)
					(thickness 0.1524)
				)
			)
		)
		(property "Device Type" "C402H22"
			(at 1.1811 -4.2291 270)
			(unlocked yes)
			(layer "F.Fab")
			(hide yes)
			(effects
				(font
					(size 1.016 1.016)
					(thickness 0.1524)
				)
			)
		)
		(duplicate_pad_numbers_are_jumpers no)
		(fp_rect
			(start -0.4318 0.9525)
			(end 0.4318 -0.9525)
			(stroke
				(width 0)
				(type default)
			)
			(fill no)
			(layer "F.CrtYd")
		)
		(fp_rect
			(start -0.4318 0.9525)
			(end 0.4318 -0.9525)
			(stroke
				(width 0)
				(type default)
			)
			(fill no)
			(layer "F.Fab")
		)
		(pad "1" smd custom
			(at 0 -0.4445 270)
			(size 0.1524 0.1524)
			(layers "F.Cu" "F.Mask" "F.Paste")
			(net "SAS2X28_DRIVE_RX_N_B1")
			(options
				(clearance outline)
				(anchor circle)
			)
			(primitives
				(gr_poly
					(pts
						(arc
							(start 0.3048 -0.2032)
							(mid 0.275042 -0.275042)
							(end 0.2032 -0.3048)
						)
						(arc
							(start -0.2032 -0.3048)
							(mid -0.275042 -0.275042)
							(end -0.3048 -0.2032)
						)
						(arc
							(start -0.3048 0.2032)
							(mid -0.275042 0.275042)
							(end -0.2032 0.3048)
						)
						(arc
							(start 0.2032 0.3048)
							(mid 0.275042 0.275042)
							(end 0.3048 0.2032)
						)
					)
					(width 0)
					(fill yes)
				)
			)
		)
		(pad "2" smd custom
			(at 0 0.4445 270)
			(size 0.1524 0.1524)
			(layers "F.Cu" "F.Mask" "F.Paste")
			(net "SAS2X28_B_HDD1_RX_-")
			(options
				(clearance outline)
				(anchor circle)
			)
			(primitives
				(gr_poly
					(pts
						(arc
							(start 0.3048 -0.2032)
							(mid 0.275042 -0.275042)
							(end 0.2032 -0.3048)
						)
						(arc
							(start -0.2032 -0.3048)
							(mid -0.275042 -0.275042)
							(end -0.3048 -0.2032)
						)
						(arc
							(start -0.3048 0.2032)
							(mid -0.275042 0.275042)
							(end -0.2032 0.3048)
						)
						(arc
							(start 0.2032 0.3048)
							(mid 0.275042 0.275042)
							(end 0.3048 0.2032)
						)
					)
					(width 0)
					(fill yes)
				)
			)
		)
	)
	(footprint ""
		(layer "F.Cu")
		(at 232.257346 -450.0118 -90)
		(property "Reference" "R488"
			(at 0 0 270)
			(layer "F.SilkS")
			(hide yes)
			(effects
				(font
					(size 1.27 1.27)
				)
			)
		)
		(property "Value" "1KR2F-3-GP"
			(at 0.064008 -3.993896 270)
			(unlocked yes)
			(layer "F.Fab")
			(hide yes)
			(effects
				(font
					(size 1.016 1.016)
					(thickness 0.1524)
				)
			)
		)
		(property "Device Type" "R402H16"
			(at 0.064008 -5.517896 270)
			(unlocked yes)
			(layer "F.Fab")
			(hide yes)
			(effects
				(font
					(size 1.016 1.016)
					(thickness 0.1524)
				)
			)
		)
		(duplicate_pad_numbers_are_jumpers no)
		(fp_line
			(start -0.508 -0.9398)
			(end -0.508 0.9398)
			(stroke
				(width 0.1524)
				(type default)
			)
			(layer "F.SilkS")
		)
		(fp_line
			(start 0.508 -0.9398)
			(end -0.508 -0.9398)
			(stroke
				(width 0.1524)
				(type default)
			)
			(layer "F.SilkS")
		)
		(fp_rect
			(start -0.508 0.9398)
			(end 0.508 -0.9398)
			(stroke
				(width 0)
				(type default)
			)
			(fill no)
			(layer "F.CrtYd")
		)
		(fp_rect
			(start -0.508 0.9398)
			(end 0.508 -0.9398)
			(stroke
				(width 0)
				(type default)
			)
			(fill no)
			(layer "F.Fab")
		)
		(pad "1" smd custom
			(at 0 -0.4445 270)
			(size 0.1397 0.1397)
			(layers "F.Cu" "F.Mask" "F.Paste")
			(net "FLT_HDD0_B")
			(options
				(clearance outline)
				(anchor circle)
			)
			(primitives
				(gr_poly
					(pts
						(arc
							(start -0.1778 -0.2794)
							(mid -0.249642 -0.249642)
							(end -0.2794 -0.1778)
						)
						(arc
							(start -0.2794 0.1778)
							(mid -0.249642 0.249642)
							(end -0.1778 0.2794)
						)
						(arc
							(start 0.1778 0.2794)
							(mid 0.249642 0.249642)
							(end 0.2794 0.1778)
						)
						(arc
							(start 0.2794 -0.1778)
							(mid 0.249642 -0.249642)
							(end 0.1778 -0.2794)
						)
					)
					(width 0)
					(fill yes)
				)
			)
		)
		(pad "2" smd custom
			(at 0 0.4445 270)
			(size 0.1397 0.1397)
			(layers "F.Cu" "F.Mask" "F.Paste")
			(net "FLT_HDD0_DRIVE")
			(options
				(clearance outline)
				(anchor circle)
			)
			(primitives
				(gr_poly
					(pts
						(arc
							(start -0.1778 -0.2794)
							(mid -0.249642 -0.249642)
							(end -0.2794 -0.1778)
						)
						(arc
							(start -0.2794 0.1778)
							(mid -0.249642 0.249642)
							(end -0.1778 0.2794)
						)
						(arc
							(start 0.1778 0.2794)
							(mid 0.249642 0.249642)
							(end 0.2794 0.1778)
						)
						(arc
							(start 0.2794 -0.1778)
							(mid 0.249642 -0.249642)
							(end 0.1778 -0.2794)
						)
					)
					(width 0)
					(fill yes)
				)
			)
		)
	)
	(footprint ""
		(layer "F.Cu")
		(at 16.705072 -500.446548 180)
		(property "Reference" "PC29"
			(at 0 0 180)
			(layer "F.SilkS")
			(hide yes)
			(effects
				(font
					(size 1.27 1.27)
				)
			)
		)
		(property "Value" "SC22U25V5MX-GP"
			(at -0.0762 -6.1214 180)
			(unlocked yes)
			(layer "F.Fab")
			(hide yes)
			(effects
				(font
					(size 1.016 1.016)
					(thickness 0.1524)
				)
			)
		)
		(property "Device Type" "C805H58"
			(at -0.0762 -8.1534 180)
			(unlocked yes)
			(layer "F.Fab")
			(hide yes)
			(effects
				(font
					(size 1.016 1.016)
					(thickness 0.1524)
				)
			)
		)
		(duplicate_pad_numbers_are_jumpers no)
		(fp_line
			(start 0.635 0)
			(end -0.635 0)
			(stroke
				(width 0.508)
				(type default)
			)
			(layer "F.SilkS")
		)
		(fp_rect
			(start -0.9652 1.778)
			(end 0.9652 -1.778)
			(stroke
				(width 0)
				(type default)
			)
			(fill no)
			(layer "F.CrtYd")
		)
		(fp_poly
			(pts
				(xy -0.9652 -1.778) (xy 0.9652 -1.778) (xy 0.9652 1.778) (xy -0.9652 1.778)
			)
			(stroke
				(width 0)
				(type default)
			)
			(fill no)
			(layer "F.Fab")
		)
		(pad "1" smd rect
			(at 0 -0.9652 180)
			(size 1.397 1.143)
			(layers "F.Cu" "F.Mask" "F.Paste")
			(net "P5VC_12VIN")
		)
		(pad "2" smd rect
			(at 0 0.9652 180)
			(size 1.397 1.143)
			(layers "F.Cu" "F.Mask" "F.Paste")
			(net "GND")
		)
	)
	(footprint ""
		(layer "F.Cu")
		(at 215.467946 -481.0379 -90)
		(property "Reference" "R343"
			(at 0 0 270)
			(layer "F.SilkS")
			(hide yes)
			(effects
				(font
					(size 1.27 1.27)
				)
			)
		)
		(property "Value" "0R2J-2-GP"
			(at 0.064008 -3.993896 270)
			(unlocked yes)
			(layer "F.Fab")
			(hide yes)
			(effects
				(font
					(size 1.016 1.016)
					(thickness 0.1524)
				)
			)
		)
		(property "Device Type" "R402H16"
			(at 0.064008 -5.517896 270)
			(unlocked yes)
			(layer "F.Fab")
			(hide yes)
			(effects
				(font
					(size 1.016 1.016)
					(thickness 0.1524)
				)
			)
		)
		(duplicate_pad_numbers_are_jumpers no)
		(fp_line
			(start -0.508 -0.9398)
			(end -0.508 0.9398)
			(stroke
				(width 0.1524)
				(type default)
			)
			(layer "F.SilkS")
		)
		(fp_line
			(start 0.508 -0.9398)
			(end -0.508 -0.9398)
			(stroke
				(width 0.1524)
				(type default)
			)
			(layer "F.SilkS")
		)
		(fp_rect
			(start -0.508 0.9398)
			(end 0.508 -0.9398)
			(stroke
				(width 0)
				(type default)
			)
			(fill no)
			(layer "F.CrtYd")
		)
		(fp_rect
			(start -0.508 0.9398)
			(end 0.508 -0.9398)
			(stroke
				(width 0)
				(type default)
			)
			(fill no)
			(layer "F.Fab")
		)
		(pad "1" smd custom
			(at 0 -0.4445 270)
			(size 0.1397 0.1397)
			(layers "F.Cu" "F.Mask" "F.Paste")
			(net "HDD_PRSNT_NET0")
			(options
				(clearance outline)
				(anchor circle)
			)
			(primitives
				(gr_poly
					(pts
						(arc
							(start -0.1778 -0.2794)
							(mid -0.249642 -0.249642)
							(end -0.2794 -0.1778)
						)
						(arc
							(start -0.2794 0.1778)
							(mid -0.249642 0.249642)
							(end -0.1778 0.2794)
						)
						(arc
							(start 0.1778 0.2794)
							(mid 0.249642 0.249642)
							(end 0.2794 0.1778)
						)
						(arc
							(start 0.2794 -0.1778)
							(mid 0.249642 -0.249642)
							(end 0.1778 -0.2794)
						)
					)
					(width 0)
					(fill yes)
				)
			)
		)
		(pad "2" smd custom
			(at 0 0.4445 270)
			(size 0.1397 0.1397)
			(layers "F.Cu" "F.Mask" "F.Paste")
			(net "HDD0_LED_B")
			(options
				(clearance outline)
				(anchor circle)
			)
			(primitives
				(gr_poly
					(pts
						(arc
							(start -0.1778 -0.2794)
							(mid -0.249642 -0.249642)
							(end -0.2794 -0.1778)
						)
						(arc
							(start -0.2794 0.1778)
							(mid -0.249642 0.249642)
							(end -0.1778 0.2794)
						)
						(arc
							(start 0.1778 0.2794)
							(mid 0.249642 0.249642)
							(end 0.2794 0.1778)
						)
						(arc
							(start 0.2794 -0.1778)
							(mid 0.249642 -0.249642)
							(end 0.1778 -0.2794)
						)
					)
					(width 0)
					(fill yes)
				)
			)
		)
	)
	(footprint ""
		(layer "F.Cu")
		(at 177.558446 -459.393036 -90)
		(property "Reference" "R386"
			(at 0 0 270)
			(layer "F.SilkS")
			(hide yes)
			(effects
				(font
					(size 1.27 1.27)
				)
			)
		)
		(property "Value" "0R2J-2-GP"
			(at 0.064008 -3.993896 270)
			(unlocked yes)
			(layer "F.Fab")
			(hide yes)
			(effects
				(font
					(size 1.016 1.016)
					(thickness 0.1524)
				)
			)
		)
		(property "Device Type" "R402H16"
			(at 0.064008 -5.517896 270)
			(unlocked yes)
			(layer "F.Fab")
			(hide yes)
			(effects
				(font
					(size 1.016 1.016)
					(thickness 0.1524)
				)
			)
		)
		(duplicate_pad_numbers_are_jumpers no)
		(fp_line
			(start -0.508 -0.9398)
			(end -0.508 0.9398)
			(stroke
				(width 0.1524)
				(type default)
			)
			(layer "F.SilkS")
		)
		(fp_line
			(start 0.508 -0.9398)
			(end -0.508 -0.9398)
			(stroke
				(width 0.1524)
				(type default)
			)
			(layer "F.SilkS")
		)
		(fp_rect
			(start -0.508 0.9398)
			(end 0.508 -0.9398)
			(stroke
				(width 0)
				(type default)
			)
			(fill no)
			(layer "F.CrtYd")
		)
		(fp_rect
			(start -0.508 0.9398)
			(end 0.508 -0.9398)
			(stroke
				(width 0)
				(type default)
			)
			(fill no)
			(layer "F.Fab")
		)
		(pad "1" smd custom
			(at 0 -0.4445 270)
			(size 0.1397 0.1397)
			(layers "F.Cu" "F.Mask" "F.Paste")
			(net "P12V_DIV")
			(options
				(clearance outline)
				(anchor circle)
			)
			(primitives
				(gr_poly
					(pts
						(arc
							(start -0.1778 -0.2794)
							(mid -0.249642 -0.249642)
							(end -0.2794 -0.1778)
						)
						(arc
							(start -0.2794 0.1778)
							(mid -0.249642 0.249642)
							(end -0.1778 0.2794)
						)
						(arc
							(start 0.1778 0.2794)
							(mid 0.249642 0.249642)
							(end 0.2794 0.1778)
						)
						(arc
							(start 0.2794 -0.1778)
							(mid 0.249642 -0.249642)
							(end 0.1778 -0.2794)
						)
					)
					(width 0)
					(fill yes)
				)
			)
		)
		(pad "2" smd custom
			(at 0 0.4445 270)
			(size 0.1397 0.1397)
			(layers "F.Cu" "F.Mask" "F.Paste")
			(net "P12V_SENSE")
			(options
				(clearance outline)
				(anchor circle)
			)
			(primitives
				(gr_poly
					(pts
						(arc
							(start -0.1778 -0.2794)
							(mid -0.249642 -0.249642)
							(end -0.2794 -0.1778)
						)
						(arc
							(start -0.2794 0.1778)
							(mid -0.249642 0.249642)
							(end -0.1778 0.2794)
						)
						(arc
							(start 0.1778 0.2794)
							(mid 0.249642 0.249642)
							(end 0.2794 0.1778)
						)
						(arc
							(start 0.2794 -0.1778)
							(mid 0.249642 -0.249642)
							(end 0.1778 -0.2794)
						)
					)
					(width 0)
					(fill yes)
				)
			)
		)
	)
	(footprint ""
		(layer "F.Cu")
		(at 207.264 -379.984)
		(property "Reference" "C365"
			(at 0 0 0)
			(layer "F.SilkS")
			(hide yes)
			(effects
				(font
					(size 1.27 1.27)
				)
			)
		)
		(property "Value" "SCD033U25V2KX-GP"
			(at 1.1811 -2.7051 0)
			(unlocked yes)
			(layer "F.Fab")
			(hide yes)
			(effects
				(font
					(size 1.016 1.016)
					(thickness 0.1524)
				)
			)
		)
		(property "Device Type" "C402H22"
			(at 1.1811 -4.2291 0)
			(unlocked yes)
			(layer "F.Fab")
			(hide yes)
			(effects
				(font
					(size 1.016 1.016)
					(thickness 0.1524)
				)
			)
		)
		(duplicate_pad_numbers_are_jumpers no)
		(fp_rect
			(start -0.4318 0.9525)
			(end 0.4318 -0.9525)
			(stroke
				(width 0)
				(type default)
			)
			(fill no)
			(layer "F.CrtYd")
		)
		(fp_rect
			(start -0.4318 0.9525)
			(end 0.4318 -0.9525)
			(stroke
				(width 0)
				(type default)
			)
			(fill no)
			(layer "F.Fab")
		)
		(pad "1" smd custom
			(at 0 -0.4445)
			(size 0.1524 0.1524)
			(layers "F.Cu" "F.Mask" "F.Paste")
			(net "SW_HDD1_P")
			(options
				(clearance outline)
				(anchor circle)
			)
			(primitives
				(gr_poly
					(pts
						(arc
							(start 0.3048 -0.2032)
							(mid 0.275042 -0.275042)
							(end 0.2032 -0.3048)
						)
						(arc
							(start -0.2032 -0.3048)
							(mid -0.275042 -0.275042)
							(end -0.3048 -0.2032)
						)
						(arc
							(start -0.3048 0.2032)
							(mid -0.275042 0.275042)
							(end -0.2032 0.3048)
						)
						(arc
							(start 0.2032 0.3048)
							(mid 0.275042 0.275042)
							(end 0.3048 0.2032)
						)
					)
					(width 0)
					(fill yes)
				)
			)
		)
		(pad "2" smd custom
			(at 0 0.4445)
			(size 0.1524 0.1524)
			(layers "F.Cu" "F.Mask" "F.Paste")
			(net "GND")
			(options
				(clearance outline)
				(anchor circle)
			)
			(primitives
				(gr_poly
					(pts
						(arc
							(start 0.3048 -0.2032)
							(mid 0.275042 -0.275042)
							(end 0.2032 -0.3048)
						)
						(arc
							(start -0.2032 -0.3048)
							(mid -0.275042 -0.275042)
							(end -0.3048 -0.2032)
						)
						(arc
							(start -0.3048 0.2032)
							(mid -0.275042 0.275042)
							(end -0.2032 0.3048)
						)
						(arc
							(start 0.2032 0.3048)
							(mid 0.275042 0.275042)
							(end 0.3048 0.2032)
						)
					)
					(width 0)
					(fill yes)
				)
			)
		)
	)
)
